# T6G (Grand Teton) — schematic netlist excerpt (pin names and nets, part order shuffled) for the footprints in the layout excerpt that follows; sources: Cadence DE-HDL packaged netlist, KiCad conversion of 04192023_DAF0TMB3IC0_F0TG_MB_C_brd_V02_OCP.brd

R1350  Q_RES  0 5% CHIP  pkg 0402LF  page 357 : A = INA230_8_A1 ; B = SMB_INA230_8_3V3AUX_SDA_R1
C894  Q_CAP_DIFFBUS  DIFF BUS_0.22UF 6.3V 20% X6S  pkg C0201  page 64 : \1\ = P5E_CPU0_P3_TX_C_DN<3> ; \2\ = P5E_CPU0_P3_TX_DN<3>
PC176  Q_CAP  560PF 50V 10% EMPTY  pkg C0402  page 223 : A = SW_PVDDIO_P1_SW4 ; B = SW_PVDDIO_P1_SW4_RC

(kicad_pcb
	(version 20260206)
	(generator "pcbnew")
	(generator_version "10.0")
	(general
		(thickness 1.6)
		(legacy_teardrops no)
	)
	(paper "A4")
	(title_block
		(title "04192023_DAF0TMB3IC0_F0TG_MB_C_brd_V02_OCP.brd")
		(comment 1 "Grand Teton / footprints 3128-3130 of 8354")
	)
	(layers
		(0 "F.Cu" signal "TOP")
		(4 "In1.Cu" signal "GND")
		(6 "In2.Cu" signal "IN1")
		(8 "In3.Cu" signal "GND1")
		(10 "In4.Cu" signal "IN2")
		(12 "In5.Cu" signal "GND2")
		(14 "In6.Cu" signal "IN3")
		(16 "In7.Cu" signal "GND3")
		(18 "In8.Cu" signal "VCC")
		(20 "In9.Cu" signal "VCC1")
		(22 "In10.Cu" signal "GND4")
		(24 "In11.Cu" signal "IN4")
		(26 "In12.Cu" signal "GND5")
		(28 "In13.Cu" signal "IN5")
		(30 "In14.Cu" signal "GND6")
		(32 "In15.Cu" signal "IN6")
		(34 "In16.Cu" signal "GND7")
		(2 "B.Cu" signal "BOTTOM")
		(9 "F.Adhes" user "F.Adhesive")
		(11 "B.Adhes" user "B.Adhesive")
		(13 "F.Paste" user "Package Geometry/Pastemask Top")
		(15 "B.Paste" user "Package Geometry/Pastemask Bottom")
		(5 "F.SilkS" user "Ref Des/Silkscreen Top")
		(7 "B.SilkS" user "Ref Des/Silkscreen Bottom")
		(1 "F.Mask" user "Board Geometry/Soldermask Top")
		(3 "B.Mask" user "Board Geometry/Soldermask Bottom")
		(17 "Dwgs.User" user "User.Drawings")
		(19 "Cmts.User" user "User.Comments")
		(21 "Eco1.User" user "User.Eco1")
		(23 "Eco2.User" user "User.Eco2")
		(25 "Edge.Cuts" user "Board Geometry/Outline")
		(27 "Margin" user)
		(31 "F.CrtYd" user "Package Geometry/Place Bound Top")
		(29 "B.CrtYd" user "Package Geometry/Place Bound Bottom")
		(35 "F.Fab" user "Ref Des/Assembly Top")
		(33 "B.Fab" user "Ref Des/Assembly Bottom")
	)
	(footprint ""
		(layer "F.Cu")
		(at 368.705892 -378.95403 -90)
		(property "Reference" "C894"
			(at 0 0 270)
			(layer "F.SilkS")
			(hide yes)
			(effects
				(font
					(size 1.27 1.27)
				)
			)
		)
		(property "Value" ""
			(at 0 0 270)
			(layer "F.Fab")
			(effects
				(font
					(size 1.27 1.27)
				)
			)
		)
		(duplicate_pad_numbers_are_jumpers no)
		(fp_line
			(start -0.299974 0.150114)
			(end -0.299974 -0.150114)
			(stroke
				(width 0.1)
				(type default)
			)
			(layer "F.Fab")
		)
		(fp_line
			(start 0.299974 0.150114)
			(end -0.299974 0.150114)
			(stroke
				(width 0.1)
				(type default)
			)
			(layer "F.Fab")
		)
		(fp_line
			(start -0.299974 -0.150114)
			(end 0.299974 -0.150114)
			(stroke
				(width 0.1)
				(type default)
			)
			(layer "F.Fab")
		)
		(fp_line
			(start 0.299974 -0.150114)
			(end 0.299974 0.150114)
			(stroke
				(width 0.1)
				(type default)
			)
			(layer "F.Fab")
		)
		(pad "1" smd rect
			(at -0.2667 0 270)
			(size 0.3048 0.381)
			(layers "F.Cu" "F.Mask" "F.Paste")
			(net "P5E_CPU0_P3_TX_C_DN<3>")
		)
		(pad "2" smd rect
			(at 0.2667 0 270)
			(size 0.3048 0.381)
			(layers "F.Cu" "F.Mask" "F.Paste")
			(net "P5E_CPU0_P3_TX_DN<3>")
		)
	)
	(footprint ""
		(layer "F.Cu")
		(at 321.056 -99.187)
		(property "Reference" "R1350"
			(at 0 0 0)
			(layer "F.SilkS")
			(hide yes)
			(effects
				(font
					(size 1.27 1.27)
				)
			)
		)
		(property "Value" ""
			(at 0 0 0)
			(layer "F.Fab")
			(effects
				(font
					(size 1.27 1.27)
				)
			)
		)
		(duplicate_pad_numbers_are_jumpers no)
		(fp_line
			(start -0.7874 -0.4064)
			(end 0.7874 -0.4064)
			(stroke
				(width 0.1524)
				(type default)
			)
			(layer "F.SilkS")
		)
		(fp_line
			(start -0.7874 0.4064)
			(end -0.7874 -0.4064)
			(stroke
				(width 0.1524)
				(type default)
			)
			(layer "F.SilkS")
		)
		(fp_line
			(start 0.7874 -0.4064)
			(end 0.7874 0.4064)
			(stroke
				(width 0.1524)
				(type default)
			)
			(layer "F.SilkS")
		)
		(fp_line
			(start 0.7874 0.4064)
			(end -0.7874 0.4064)
			(stroke
				(width 0.1524)
				(type default)
			)
			(layer "F.SilkS")
		)
		(fp_line
			(start -0.67945 -0.305054)
			(end -0.12065 -0.305054)
			(stroke
				(width 0.1)
				(type default)
			)
			(layer "F.Fab")
		)
		(fp_line
			(start -0.67945 0.3048)
			(end -0.67945 -0.305054)
			(stroke
				(width 0.1)
				(type default)
			)
			(layer "F.Fab")
		)
		(fp_line
			(start -0.12065 -0.305054)
			(end -0.12065 -0.2794)
			(stroke
				(width 0.1)
				(type default)
			)
			(layer "F.Fab")
		)
		(fp_line
			(start -0.12065 -0.2794)
			(end 0.12065 -0.2794)
			(stroke
				(width 0.1)
				(type default)
			)
			(layer "F.Fab")
		)
		(fp_line
			(start -0.12065 0.2794)
			(end -0.12065 0.3048)
			(stroke
				(width 0.1)
				(type default)
			)
			(layer "F.Fab")
		)
		(fp_line
			(start -0.12065 0.3048)
			(end -0.67945 0.3048)
			(stroke
				(width 0.1)
				(type default)
			)
			(layer "F.Fab")
		)
		(fp_line
			(start 0.120396 0.2794)
			(end -0.12065 0.2794)
			(stroke
				(width 0.1)
				(type default)
			)
			(layer "F.Fab")
		)
		(fp_line
			(start 0.120396 0.3048)
			(end 0.120396 0.2794)
			(stroke
				(width 0.1)
				(type default)
			)
			(layer "F.Fab")
		)
		(fp_line
			(start 0.12065 -0.3048)
			(end 0.67945 -0.3048)
			(stroke
				(width 0.1)
				(type default)
			)
			(layer "F.Fab")
		)
		(fp_line
			(start 0.12065 -0.2794)
			(end 0.12065 -0.3048)
			(stroke
				(width 0.1)
				(type default)
			)
			(layer "F.Fab")
		)
		(fp_line
			(start 0.67945 -0.3048)
			(end 0.67945 0.3048)
			(stroke
				(width 0.1)
				(type default)
			)
			(layer "F.Fab")
		)
		(fp_line
			(start 0.67945 0.3048)
			(end 0.120396 0.3048)
			(stroke
				(width 0.1)
				(type default)
			)
			(layer "F.Fab")
		)
		(pad "1" smd circle
			(at -0.40005 0)
			(size 0 0)
			(layers "F.Cu" "F.Mask" "F.Paste")
			(net "INA230_8_A1")
		)
		(pad "2" smd circle
			(at 0.40005 0)
			(size 0 0)
			(layers "F.Cu" "F.Mask" "F.Paste")
			(net "SMB_INA230_8_3V3AUX_SDA_R1")
		)
	)
	(footprint ""
		(layer "F.Cu")
		(at 24.906732 -343.716864 180)
		(property "Reference" "PC176"
			(at 0 0 180)
			(layer "F.SilkS")
			(hide yes)
			(effects
				(font
					(size 1.27 1.27)
				)
			)
		)
		(property "Value" ""
			(at 0 0 180)
			(layer "F.Fab")
			(effects
				(font
					(size 1.27 1.27)
				)
			)
		)
		(duplicate_pad_numbers_are_jumpers no)
		(fp_line
			(start 0.7874 0.4064)
			(end -0.7874 0.4064)
			(stroke
				(width 0.1524)
				(type default)
			)
			(layer "F.SilkS")
		)
		(fp_line
			(start 0.7874 -0.4064)
			(end 0.7874 0.4064)
			(stroke
				(width 0.1524)
				(type default)
			)
			(layer "F.SilkS")
		)
		(fp_line
			(start -0.7874 0.4064)
			(end -0.7874 -0.4064)
			(stroke
				(width 0.1524)
				(type default)
			)
			(layer "F.SilkS")
		)
		(fp_line
			(start -0.7874 -0.4064)
			(end 0.7874 -0.4064)
			(stroke
				(width 0.1524)
				(type default)
			)
			(layer "F.SilkS")
		)
		(fp_line
			(start 0.67945 0.3048)
			(end 0.120396 0.3048)
			(stroke
				(width 0.1)
				(type default)
			)
			(layer "F.Fab")
		)
		(fp_line
			(start 0.67945 -0.3048)
			(end 0.67945 0.3048)
			(stroke
				(width 0.1)
				(type default)
			)
			(layer "F.Fab")
		)
		(fp_line
			(start 0.12065 -0.2794)
			(end 0.12065 -0.3048)
			(stroke
				(width 0.1)
				(type default)
			)
			(layer "F.Fab")
		)
		(fp_line
			(start 0.12065 -0.3048)
			(end 0.67945 -0.3048)
			(stroke
				(width 0.1)
				(type default)
			)
			(layer "F.Fab")
		)
		(fp_line
			(start 0.120396 0.3048)
			(end 0.120396 0.2794)
			(stroke
				(width 0.1)
				(type default)
			)
			(layer "F.Fab")
		)
		(fp_line
			(start 0.120396 0.2794)
			(end -0.12065 0.2794)
			(stroke
				(width 0.1)
				(type default)
			)
			(layer "F.Fab")
		)
		(fp_line
			(start -0.12065 0.3048)
			(end -0.67945 0.3048)
			(stroke
				(width 0.1)
				(type default)
			)
			(layer "F.Fab")
		)
		(fp_line
			(start -0.12065 0.2794)
			(end -0.12065 0.3048)
			(stroke
				(width 0.1)
				(type default)
			)
			(layer "F.Fab")
		)
		(fp_line
			(start -0.12065 -0.2794)
			(end 0.12065 -0.2794)
			(stroke
				(width 0.1)
				(type default)
			)
			(layer "F.Fab")
		)
		(fp_line
			(start -0.12065 -0.305054)
			(end -0.12065 -0.2794)
			(stroke
				(width 0.1)
				(type default)
			)
			(layer "F.Fab")
		)
		(fp_line
			(start -0.67945 0.3048)
			(end -0.67945 -0.305054)
			(stroke
				(width 0.1)
				(type default)
			)
			(layer "F.Fab")
		)
		(fp_line
			(start -0.67945 -0.305054)
			(end -0.12065 -0.305054)
			(stroke
				(width 0.1)
				(type default)
			)
			(layer "F.Fab")
		)
		(pad "1" smd circle
			(at -0.40005 0 180)
			(size 0 0)
			(layers "F.Cu" "F.Mask" "F.Paste")
			(net "SW_PVDDIO_P1_SW4")
		)
		(pad "2" smd circle
			(at 0.40005 0 180)
			(size 0 0)
			(layers "F.Cu" "F.Mask" "F.Paste")
			(net "SW_PVDDIO_P1_SW4_RC")
		)
	)
)
